(kicad_pcb
	(version 20221018)
	(generator pcbnew)
	(general
    (thickness 1.656)
  )
	(paper "A4")
	(title_block
    (title "SDI-MIPI Bridge")
    (date "2023-08-09")
    (rev "1.3.4")
    (company "Antmicro")
		(comment 9 "footprints 185-190 of 190")
	)
	(layers
    (0 "F.Cu" signal)
    (1 "In1.Cu" power)
    (2 "In2.Cu" power)
    (3 "In3.Cu" signal)
    (4 "In4.Cu" signal)
    (31 "B.Cu" signal)
    (32 "B.Adhes" user "B.Adhesive")
    (33 "F.Adhes" user "F.Adhesive")
    (34 "B.Paste" user)
    (35 "F.Paste" user)
    (36 "B.SilkS" user "B.Silkscreen")
    (37 "F.SilkS" user "F.Silkscreen")
    (38 "B.Mask" user)
    (39 "F.Mask" user)
    (40 "Dwgs.User" user "User.Drawings")
    (41 "Cmts.User" user "User.Comments")
    (42 "Eco1.User" user "User.Eco1")
    (43 "Eco2.User" user "User.Eco2")
    (44 "Edge.Cuts" user)
    (45 "Margin" user)
    (46 "B.CrtYd" user "B.Courtyard")
    (47 "F.CrtYd" user "F.Courtyard")
    (48 "B.Fab" user)
    (49 "F.Fab" user)
  )
	(footprint "sdi-mipi-bridge-footprints:R_0402_1005Metric" (layer "B.Cu")
    (at 141.85 109.525 -90)
    (descr "Resistor SMD 0402")
    (tags "resistor SMD 0402")
    (property "Author" "Antmicro")
    (property "License" "Apache-2.0")
    (property "MPN" "CR0402-FX-4701GLF")
    (property "Manufacturer" "Bourns")
    (property "Sheetfile" "sdi-mipi-bridge.kicad_sch")
    (property "Sheetname" "")
    (property "Tolerance" "1%")
    (property "Val" "4k7")
    (property "ki_description" "4k7 resistor in 0402 package with 1% tolerance")
    (attr smd)
    (fp_text reference "R95" (at -5.125 2.7675 90) (layer "B.SilkS")
        (effects (font (size 0.7 0.7) (thickness 0.15)) (justify left bottom mirror))
    )
    (fp_text value "R_4k7_0402" (at 0 -1.4 90) (layer "B.Fab") hide
        (effects (font (size 0.7 0.7) (thickness 0.15)) (justify left bottom mirror))
    )
    (fp_text user "${REFERENCE}" (at -0.95 -3.168 90) (layer "B.Fab") hide
        (effects (font (size 0.7 0.7) (thickness 0.15)) (justify left bottom mirror))
    )
    (fp_text user "Author: Antmicro" (at -0.95 -4.169 90) (layer "B.Fab") hide
        (effects (font (size 0.7 0.7) (thickness 0.15)) (justify left bottom mirror))
    )
    (fp_text user "License: Apache-2.0" (at -0.95 -5.169 90) (layer "B.Fab") hide
        (effects (font (size 0.7 0.7) (thickness 0.15)) (justify left bottom mirror))
    )
    (fp_rect (start -0.93 0.47) (end 0.93 -0.47)
      (stroke (width 0.05) (type solid)) (fill none) (layer "B.CrtYd"))
    (fp_rect (start -0.5 0.25) (end 0.5 -0.25)
      (stroke (width 0.15) (type solid)) (fill none) (layer "B.Fab"))
    (pad "1" smd roundrect (at -0.485 0 270) (size 0.59 0.64) (layers "B.Cu" "B.Paste" "B.Mask") (roundrect_rratio 0.25)
      (net 99 "/SPI_SS(SCL)") (pintype "passive"))
    (pad "2" smd roundrect (at 0.485 0 270) (size 0.59 0.64) (layers "B.Cu" "B.Paste" "B.Mask") (roundrect_rratio 0.25)
      (net 79 "VCC_IO") (pintype "passive"))
  )
	(footprint "sdi-mipi-bridge-footprints:R_0402_1005Metric" (layer "B.Cu")
    (at 130.4 129.025)
    (descr "Resistor SMD 0402")
    (tags "resistor SMD 0402")
    (property "Author" "Antmicro")
    (property "Current" "1A")
    (property "License" "Apache-2.0")
    (property "MPN" "ERJ2GE0R00X")
    (property "Manufacturer" "Panasonic")
    (property "Sheetfile" "sdi-mipi-bridge.kicad_sch")
    (property "Sheetname" "")
    (property "Tolerance" "")
    (property "Val" "0R")
    (property "ki_description" "0R resistor in 0402 package with unspecified tolerance")
    (attr smd)
    (fp_text reference "R25" (at -1 0.3 180) (layer "B.SilkS")
        (effects (font (size 0.7 0.7) (thickness 0.15)) (justify left bottom mirror))
    )
    (fp_text value "R_0R_0402" (at 0 -1.4 180) (layer "B.Fab") hide
        (effects (font (size 0.7 0.7) (thickness 0.15)) (justify left bottom mirror))
    )
    (fp_text user "Author: Antmicro" (at -0.95 -4.169 180) (layer "B.Fab") hide
        (effects (font (size 0.7 0.7) (thickness 0.15)) (justify left bottom mirror))
    )
    (fp_text user "${REFERENCE}" (at -0.95 -3.168 180) (layer "B.Fab") hide
        (effects (font (size 0.7 0.7) (thickness 0.15)) (justify left bottom mirror))
    )
    (fp_text user "License: Apache-2.0" (at -0.95 -5.169 180) (layer "B.Fab") hide
        (effects (font (size 0.7 0.7) (thickness 0.15)) (justify left bottom mirror))
    )
    (fp_rect (start -0.93 0.47) (end 0.93 -0.47)
      (stroke (width 0.05) (type solid)) (fill none) (layer "B.CrtYd"))
    (fp_rect (start -0.5 0.25) (end 0.5 -0.25)
      (stroke (width 0.15) (type solid)) (fill none) (layer "B.Fab"))
    (pad "1" smd roundrect (at -0.485 0) (size 0.59 0.64) (layers "B.Cu" "B.Paste" "B.Mask") (roundrect_rratio 0.25)
      (net 6 "+3V3") (pintype "passive"))
    (pad "2" smd roundrect (at 0.485 0) (size 0.59 0.64) (layers "B.Cu" "B.Paste" "B.Mask") (roundrect_rratio 0.25)
      (net 76 "IO_VDD") (pintype "passive"))
  )
	(footprint "sdi-mipi-bridge-footprints:R_0402_1005Metric" (layer "B.Cu")
    (at 111.75 134.25 90)
    (descr "Resistor SMD 0402")
    (tags "resistor SMD 0402")
    (property "Author" "Antmicro")
    (property "Current" "1A")
    (property "License" "Apache-2.0")
    (property "MPN" "ERJ2GE0R00X")
    (property "Manufacturer" "Panasonic")
    (property "Sheetfile" "sdi-mipi-bridge.kicad_sch")
    (property "Sheetname" "")
    (property "Tolerance" "")
    (property "Val" "0R")
    (property "ki_description" "0R resistor in 0402 package with unspecified tolerance")
    (attr smd)
    (fp_text reference "R24" (at 3.65 0.45 270) (layer "B.SilkS")
        (effects (font (size 0.7 0.7) (thickness 0.15)) (justify left bottom mirror))
    )
    (fp_text value "R_0R_0402" (at 0 -1.4 270) (layer "B.Fab") hide
        (effects (font (size 0.7 0.7) (thickness 0.15)) (justify left bottom mirror))
    )
    (fp_text user "Author: Antmicro" (at -0.95 -4.169 270) (layer "B.Fab") hide
        (effects (font (size 0.7 0.7) (thickness 0.15)) (justify left bottom mirror))
    )
    (fp_text user "License: Apache-2.0" (at -0.95 -5.169 270) (layer "B.Fab") hide
        (effects (font (size 0.7 0.7) (thickness 0.15)) (justify left bottom mirror))
    )
    (fp_text user "${REFERENCE}" (at -0.95 -3.168 270) (layer "B.Fab") hide
        (effects (font (size 0.7 0.7) (thickness 0.15)) (justify left bottom mirror))
    )
    (fp_rect (start -0.93 0.47) (end 0.93 -0.47)
      (stroke (width 0.05) (type solid)) (fill none) (layer "B.CrtYd"))
    (fp_rect (start -0.5 0.25) (end 0.5 -0.25)
      (stroke (width 0.15) (type solid)) (fill none) (layer "B.Fab"))
    (pad "1" smd roundrect (at -0.485 0 90) (size 0.59 0.64) (layers "B.Cu" "B.Paste" "B.Mask") (roundrect_rratio 0.25)
      (net 6 "+3V3") (pintype "passive"))
    (pad "2" smd roundrect (at 0.485 0 90) (size 0.59 0.64) (layers "B.Cu" "B.Paste" "B.Mask") (roundrect_rratio 0.25)
      (net 57 "VDD") (pintype "passive"))
  )
	(footprint "sdi-mipi-bridge-footprints:C_0402_1005Metric" (layer "B.Cu")
    (at 126.1 131.53 180)
    (descr "Capacitor SMD 0402")
    (tags "capacitor SMD 0402")
    (property "Author" "Antmicro")
    (property "Dielectric" "X7R")
    (property "License" "Apache-2.0")
    (property "MPN" "GRM155R71H103KA88D")
    (property "Manufacturer" "Murata")
    (property "Sheetfile" "sdi-mipi-bridge.kicad_sch")
    (property "Sheetname" "")
    (property "Val" "10n")
    (property "Voltage" "50V")
    (property "ki_description" " ")
    (attr smd)
    (fp_text reference "C32" (at 1.301 -0.35) (layer "B.SilkS")
        (effects (font (size 0.7 0.7) (thickness 0.15)) (justify left bottom mirror))
    )
    (fp_text value "C_10n_0402" (at -100.01 -1.42) (layer "B.Fab") hide
        (effects (font (size 0.7 0.7) (thickness 0.15)) (justify left bottom mirror))
    )
    (fp_text user "${REFERENCE}" (at -0.932 -3.168) (layer "B.Fab") hide
        (effects (font (size 0.7 0.7) (thickness 0.15)) (justify left bottom mirror))
    )
    (fp_text user "License: Apache-2.0" (at -0.932 -5.17) (layer "B.Fab") hide
        (effects (font (size 0.7 0.7) (thickness 0.15)) (justify left bottom mirror))
    )
    (fp_text user "Author: Antmicro" (at -0.932 -4.17) (layer "B.Fab") hide
        (effects (font (size 0.7 0.7) (thickness 0.15)) (justify left bottom mirror))
    )
    (fp_rect (start -0.94 0.47) (end 0.94 -0.47)
      (stroke (width 0.05) (type solid)) (fill none) (layer "B.CrtYd"))
    (fp_rect (start -0.499 0.249) (end 0.499 -0.249)
      (stroke (width 0.15) (type solid)) (fill none) (layer "B.Fab"))
    (pad "1" smd roundrect (at -0.484 0 180) (size 0.59 0.64) (layers "B.Cu" "B.Paste" "B.Mask") (roundrect_rratio 0.25)
      (net 3 "GNDA") (pintype "passive"))
    (pad "2" smd roundrect (at 0.484 0 180) (size 0.59 0.64) (layers "B.Cu" "B.Paste" "B.Mask") (roundrect_rratio 0.25)
      (net 5 "+3.3VA") (pintype "passive"))
  )
	(footprint "sdi-mipi-bridge-footprints:R_0402_1005Metric" (layer "B.Cu")
    (at 129.5 110.9 90)
    (descr "Resistor SMD 0402")
    (tags "resistor SMD 0402")
    (property "Author" "Antmicro")
    (property "Current" "1A")
    (property "License" "Apache-2.0")
    (property "MPN" "ERJ2GE0R00X")
    (property "Manufacturer" "Panasonic")
    (property "Sheetfile" "sdi-mipi-bridge.kicad_sch")
    (property "Sheetname" "")
    (property "Tolerance" "")
    (property "Val" "0R")
    (property "ki_description" "0R resistor in 0402 package with unspecified tolerance")
    (attr smd)
    (fp_text reference "R105" (at -0.9 0.3 90) (layer "B.SilkS")
        (effects (font (size 0.7 0.7) (thickness 0.15)) (justify left bottom mirror))
    )
    (fp_text value "R_0R_0402" (at 0 -1.4 90) (layer "B.Fab") hide
        (effects (font (size 0.7 0.7) (thickness 0.15)) (justify right bottom mirror))
    )
    (fp_text user "${REFERENCE}" (at -0.95 -3.168 90) (layer "B.Fab") hide
        (effects (font (size 0.7 0.7) (thickness 0.15)) (justify right bottom mirror))
    )
    (fp_text user "License: Apache-2.0" (at -0.95 -5.169 90) (layer "B.Fab") hide
        (effects (font (size 0.7 0.7) (thickness 0.15)) (justify right bottom mirror))
    )
    (fp_text user "Author: Antmicro" (at -0.95 -4.169 90) (layer "B.Fab") hide
        (effects (font (size 0.7 0.7) (thickness 0.15)) (justify right bottom mirror))
    )
    (fp_rect (start -0.93 0.47) (end 0.93 -0.47)
      (stroke (width 0.05) (type solid)) (fill none) (layer "B.CrtYd"))
    (fp_rect (start -0.5 0.25) (end 0.5 -0.25)
      (stroke (width 0.15) (type solid)) (fill none) (layer "B.Fab"))
    (pad "1" smd roundrect (at -0.485 0 90) (size 0.59 0.64) (layers "B.Cu" "B.Paste" "B.Mask") (roundrect_rratio 0.25)
      (net 127 "/~{RST_TRST_SOFT}") (pintype "passive"))
    (pad "2" smd roundrect (at 0.485 0 90) (size 0.59 0.64) (layers "B.Cu" "B.Paste" "B.Mask") (roundrect_rratio 0.25)
      (net 126 "/~{RST_TRST}") (pintype "passive"))
  )
	(footprint "sdi-mipi-bridge-footprints:R_0402_1005Metric" (layer "B.Cu")
    (at 128.5 110.9 -90)
    (descr "Resistor SMD 0402")
    (tags "resistor SMD 0402")
    (property "Author" "Antmicro")
    (property "License" "Apache-2.0")
    (property "MPN" "CR0402-FX-1002GLF")
    (property "Manufacturer" "Bourns")
    (property "Sheetfile" "sdi-mipi-bridge.kicad_sch")
    (property "Sheetname" "")
    (property "Tolerance" "1%")
    (property "Val" "10k")
    (property "ki_description" "10k resistor in 0402 package with 1% tolerance")
    (attr smd)
    (fp_text reference "R98" (at 0.9 -0.3 90) (layer "B.SilkS")
        (effects (font (size 0.7 0.7) (thickness 0.15)) (justify left bottom mirror))
    )
    (fp_text value "R_10k_0402" (at 0 -1.4 90) (layer "B.Fab") hide
        (effects (font (size 0.7 0.7) (thickness 0.15)) (justify left bottom mirror))
    )
    (fp_text user "License: Apache-2.0" (at -0.95 -5.169 90) (layer "B.Fab") hide
        (effects (font (size 0.7 0.7) (thickness 0.15)) (justify left bottom mirror))
    )
    (fp_text user "${REFERENCE}" (at -0.95 -3.168 90) (layer "B.Fab") hide
        (effects (font (size 0.7 0.7) (thickness 0.15)) (justify left bottom mirror))
    )
    (fp_text user "Author: Antmicro" (at -0.95 -4.169 90) (layer "B.Fab") hide
        (effects (font (size 0.7 0.7) (thickness 0.15)) (justify left bottom mirror))
    )
    (fp_rect (start -0.93 0.47) (end 0.93 -0.47)
      (stroke (width 0.05) (type solid)) (fill none) (layer "B.CrtYd"))
    (fp_rect (start -0.5 0.25) (end 0.5 -0.25)
      (stroke (width 0.15) (type solid)) (fill none) (layer "B.Fab"))
    (pad "1" smd roundrect (at -0.485 0 270) (size 0.59 0.64) (layers "B.Cu" "B.Paste" "B.Mask") (roundrect_rratio 0.25)
      (net 3 "GNDA") (pintype "passive"))
    (pad "2" smd roundrect (at 0.485 0 270) (size 0.59 0.64) (layers "B.Cu" "B.Paste" "B.Mask") (roundrect_rratio 0.25)
      (net 126 "/~{RST_TRST}") (pintype "passive"))
  )
)
